(kicad_pcb
	(version 20260206)
	(generator "pcbnew")
	(generator_version "10.0")
	(general
		(thickness 1.6)
		(legacy_teardrops no)
	)
	(paper "A4")
	(title_block
		(title "04192023_DAF0TMB3IC0_F0TG_MB_C_brd_V02_OCP.brd")
		(comment 1 "Grand Teton / footprints 1417-1423 of 8354")
	)
	(layers
		(0 "F.Cu" signal "TOP")
		(4 "In1.Cu" signal "GND")
		(6 "In2.Cu" signal "IN1")
		(8 "In3.Cu" signal "GND1")
		(10 "In4.Cu" signal "IN2")
		(12 "In5.Cu" signal "GND2")
		(14 "In6.Cu" signal "IN3")
		(16 "In7.Cu" signal "GND3")
		(18 "In8.Cu" signal "VCC")
		(20 "In9.Cu" signal "VCC1")
		(22 "In10.Cu" signal "GND4")
		(24 "In11.Cu" signal "IN4")
		(26 "In12.Cu" signal "GND5")
		(28 "In13.Cu" signal "IN5")
		(30 "In14.Cu" signal "GND6")
		(32 "In15.Cu" signal "IN6")
		(34 "In16.Cu" signal "GND7")
		(2 "B.Cu" signal "BOTTOM")
		(9 "F.Adhes" user "F.Adhesive")
		(11 "B.Adhes" user "B.Adhesive")
		(13 "F.Paste" user "Package Geometry/Pastemask Top")
		(15 "B.Paste" user "Package Geometry/Pastemask Bottom")
		(5 "F.SilkS" user "Ref Des/Silkscreen Top")
		(7 "B.SilkS" user "Ref Des/Silkscreen Bottom")
		(1 "F.Mask" user "Board Geometry/Soldermask Top")
		(3 "B.Mask" user "Board Geometry/Soldermask Bottom")
		(17 "Dwgs.User" user "User.Drawings")
		(19 "Cmts.User" user "User.Comments")
		(21 "Eco1.User" user "User.Eco1")
		(23 "Eco2.User" user "User.Eco2")
		(25 "Edge.Cuts" user "Board Geometry/Outline")
		(27 "Margin" user)
		(31 "F.CrtYd" user "Package Geometry/Place Bound Top")
		(29 "B.CrtYd" user "Package Geometry/Place Bound Bottom")
		(35 "F.Fab" user "Ref Des/Assembly Top")
		(33 "B.Fab" user "Ref Des/Assembly Bottom")
	)
	(footprint ""
		(layer "F.Cu")
		(at 21.096478 -16.099536 90)
		(property "Reference" "C682"
			(at 0 0 90)
			(layer "F.SilkS")
			(hide yes)
			(effects
				(font
					(size 1.27 1.27)
				)
			)
		)
		(property "Value" ""
			(at 0 0 90)
			(layer "F.Fab")
			(effects
				(font
					(size 1.27 1.27)
				)
			)
		)
		(duplicate_pad_numbers_are_jumpers no)
		(fp_line
			(start 0.299974 -0.150114)
			(end 0.299974 0.150114)
			(stroke
				(width 0.1)
				(type default)
			)
			(layer "F.Fab")
		)
		(fp_line
			(start -0.299974 -0.150114)
			(end 0.299974 -0.150114)
			(stroke
				(width 0.1)
				(type default)
			)
			(layer "F.Fab")
		)
		(fp_line
			(start 0.299974 0.150114)
			(end -0.299974 0.150114)
			(stroke
				(width 0.1)
				(type default)
			)
			(layer "F.Fab")
		)
		(fp_line
			(start -0.299974 0.150114)
			(end -0.299974 -0.150114)
			(stroke
				(width 0.1)
				(type default)
			)
			(layer "F.Fab")
		)
		(pad "1" smd rect
			(at -0.2667 0 90)
			(size 0.3048 0.381)
			(layers "F.Cu" "F.Mask" "F.Paste")
			(net "P5E_CPU1_G1_TX_C_DN<13>")
		)
		(pad "2" smd rect
			(at 0.2667 0 90)
			(size 0.3048 0.381)
			(layers "F.Cu" "F.Mask" "F.Paste")
			(net "P5E_CPU1_G1_TX_DN<13>")
		)
	)
	(footprint ""
		(layer "F.Cu")
		(at 248.210578 -277.433532)
		(property "Reference" "PC6800"
			(at -1.068578 -4.352798 0)
			(unlocked yes)
			(layer "F.SilkS")
			(effects
				(font
					(size 0.7874 0.5842)
					(thickness 0.1524)
				)
				(justify left)
			)
		)
		(property "Value" ""
			(at 0 0 0)
			(layer "F.Fab")
			(effects
				(font
					(size 1.27 1.27)
				)
			)
		)
		(duplicate_pad_numbers_are_jumpers no)
		(fp_line
			(start -3.400044 -2.146046)
			(end -3.400044 -0.9398)
			(stroke
				(width 0.1524)
				(type default)
			)
			(layer "F.SilkS")
		)
		(fp_line
			(start -3.400044 2.146046)
			(end -3.400044 0.9398)
			(stroke
				(width 0.1524)
				(type default)
			)
			(layer "F.SilkS")
		)
		(fp_line
			(start -2.146046 -3.400044)
			(end -3.400044 -2.146046)
			(stroke
				(width 0.1524)
				(type default)
			)
			(layer "F.SilkS")
		)
		(fp_line
			(start -2.146046 3.400044)
			(end -3.400044 2.146046)
			(stroke
				(width 0.1524)
				(type default)
			)
			(layer "F.SilkS")
		)
		(fp_line
			(start 3.400044 -3.400044)
			(end -2.146046 -3.400044)
			(stroke
				(width 0.1524)
				(type default)
			)
			(layer "F.SilkS")
		)
		(fp_line
			(start 3.400044 -0.9398)
			(end 3.400044 -3.400044)
			(stroke
				(width 0.1524)
				(type default)
			)
			(layer "F.SilkS")
		)
		(fp_line
			(start 3.400044 0.9398)
			(end 3.400044 3.400044)
			(stroke
				(width 0.1524)
				(type default)
			)
			(layer "F.SilkS")
		)
		(fp_line
			(start 3.400044 3.400044)
			(end -2.146046 3.400044)
			(stroke
				(width 0.1524)
				(type default)
			)
			(layer "F.SilkS")
		)
		(fp_line
			(start -3.400044 -3.400044)
			(end -3.400044 3.400044)
			(stroke
				(width 0.1)
				(type default)
			)
			(layer "F.Fab")
		)
		(fp_line
			(start -3.400044 3.400044)
			(end 3.400044 3.400044)
			(stroke
				(width 0.1)
				(type default)
			)
			(layer "F.Fab")
		)
		(fp_line
			(start 3.400044 -3.400044)
			(end -3.400044 -3.400044)
			(stroke
				(width 0.1)
				(type default)
			)
			(layer "F.Fab")
		)
		(fp_line
			(start 3.400044 3.400044)
			(end 3.400044 -3.400044)
			(stroke
				(width 0.1)
				(type default)
			)
			(layer "F.Fab")
		)
		(pad "1" smd rect
			(at -2.70002 0 270)
			(size 1.6002 3.5052)
			(layers "F.Cu" "F.Mask" "F.Paste")
			(net "SW_P12V_AUX_P1V8_RETIMER_CPU0_FLT")
		)
		(pad "2" smd rect
			(at 2.70002 0 270)
			(size 1.6002 3.5052)
			(layers "F.Cu" "F.Mask" "F.Paste")
			(net "GND")
		)
	)
	(footprint ""
		(layer "F.Cu")
		(at 178.71694 -399.420842 180)
		(property "Reference" "PR1131"
			(at 0 0 180)
			(layer "F.SilkS")
			(hide yes)
			(effects
				(font
					(size 1.27 1.27)
				)
			)
		)
		(property "Value" ""
			(at 0 0 180)
			(layer "F.Fab")
			(effects
				(font
					(size 1.27 1.27)
				)
			)
		)
		(duplicate_pad_numbers_are_jumpers no)
		(fp_line
			(start 0.7874 0.4064)
			(end -0.7874 0.4064)
			(stroke
				(width 0.1524)
				(type default)
			)
			(layer "F.SilkS")
		)
		(fp_line
			(start 0.7874 -0.4064)
			(end 0.7874 0.4064)
			(stroke
				(width 0.1524)
				(type default)
			)
			(layer "F.SilkS")
		)
		(fp_line
			(start -0.7874 0.4064)
			(end -0.7874 -0.4064)
			(stroke
				(width 0.1524)
				(type default)
			)
			(layer "F.SilkS")
		)
		(fp_line
			(start -0.7874 -0.4064)
			(end 0.7874 -0.4064)
			(stroke
				(width 0.1524)
				(type default)
			)
			(layer "F.SilkS")
		)
		(fp_line
			(start 0.67945 0.3048)
			(end 0.120396 0.3048)
			(stroke
				(width 0.1)
				(type default)
			)
			(layer "F.Fab")
		)
		(fp_line
			(start 0.67945 -0.3048)
			(end 0.67945 0.3048)
			(stroke
				(width 0.1)
				(type default)
			)
			(layer "F.Fab")
		)
		(fp_line
			(start 0.12065 -0.2794)
			(end 0.12065 -0.3048)
			(stroke
				(width 0.1)
				(type default)
			)
			(layer "F.Fab")
		)
		(fp_line
			(start 0.12065 -0.3048)
			(end 0.67945 -0.3048)
			(stroke
				(width 0.1)
				(type default)
			)
			(layer "F.Fab")
		)
		(fp_line
			(start 0.120396 0.3048)
			(end 0.120396 0.2794)
			(stroke
				(width 0.1)
				(type default)
			)
			(layer "F.Fab")
		)
		(fp_line
			(start 0.120396 0.2794)
			(end -0.12065 0.2794)
			(stroke
				(width 0.1)
				(type default)
			)
			(layer "F.Fab")
		)
		(fp_line
			(start -0.12065 0.3048)
			(end -0.67945 0.3048)
			(stroke
				(width 0.1)
				(type default)
			)
			(layer "F.Fab")
		)
		(fp_line
			(start -0.12065 0.2794)
			(end -0.12065 0.3048)
			(stroke
				(width 0.1)
				(type default)
			)
			(layer "F.Fab")
		)
		(fp_line
			(start -0.12065 -0.2794)
			(end 0.12065 -0.2794)
			(stroke
				(width 0.1)
				(type default)
			)
			(layer "F.Fab")
		)
		(fp_line
			(start -0.12065 -0.305054)
			(end -0.12065 -0.2794)
			(stroke
				(width 0.1)
				(type default)
			)
			(layer "F.Fab")
		)
		(fp_line
			(start -0.67945 0.3048)
			(end -0.67945 -0.305054)
			(stroke
				(width 0.1)
				(type default)
			)
			(layer "F.Fab")
		)
		(fp_line
			(start -0.67945 -0.305054)
			(end -0.12065 -0.305054)
			(stroke
				(width 0.1)
				(type default)
			)
			(layer "F.Fab")
		)
		(pad "1" smd circle
			(at -0.40005 0 180)
			(size 0 0)
			(layers "F.Cu" "F.Mask" "F.Paste")
			(net "HSC_CS")
		)
		(pad "2" smd circle
			(at 0.40005 0 180)
			(size 0 0)
			(layers "F.Cu" "F.Mask" "F.Paste")
			(net "AGND_HSC")
		)
	)
	(footprint ""
		(layer "F.Cu")
		(at 150.502366 -54.172358 180)
		(property "Reference" "R3560"
			(at 0 0 180)
			(layer "F.SilkS")
			(hide yes)
			(effects
				(font
					(size 1.27 1.27)
				)
			)
		)
		(property "Value" ""
			(at 0 0 180)
			(layer "F.Fab")
			(effects
				(font
					(size 1.27 1.27)
				)
			)
		)
		(duplicate_pad_numbers_are_jumpers no)
		(fp_line
			(start 0.7874 0.4064)
			(end -0.7874 0.4064)
			(stroke
				(width 0.1524)
				(type default)
			)
			(layer "F.SilkS")
		)
		(fp_line
			(start 0.7874 -0.4064)
			(end 0.7874 0.4064)
			(stroke
				(width 0.1524)
				(type default)
			)
			(layer "F.SilkS")
		)
		(fp_line
			(start -0.7874 0.4064)
			(end -0.7874 -0.4064)
			(stroke
				(width 0.1524)
				(type default)
			)
			(layer "F.SilkS")
		)
		(fp_line
			(start -0.7874 -0.4064)
			(end 0.7874 -0.4064)
			(stroke
				(width 0.1524)
				(type default)
			)
			(layer "F.SilkS")
		)
		(fp_line
			(start 0.67945 0.3048)
			(end 0.120396 0.3048)
			(stroke
				(width 0.1)
				(type default)
			)
			(layer "F.Fab")
		)
		(fp_line
			(start 0.67945 -0.3048)
			(end 0.67945 0.3048)
			(stroke
				(width 0.1)
				(type default)
			)
			(layer "F.Fab")
		)
		(fp_line
			(start 0.12065 -0.2794)
			(end 0.12065 -0.3048)
			(stroke
				(width 0.1)
				(type default)
			)
			(layer "F.Fab")
		)
		(fp_line
			(start 0.12065 -0.3048)
			(end 0.67945 -0.3048)
			(stroke
				(width 0.1)
				(type default)
			)
			(layer "F.Fab")
		)
		(fp_line
			(start 0.120396 0.3048)
			(end 0.120396 0.2794)
			(stroke
				(width 0.1)
				(type default)
			)
			(layer "F.Fab")
		)
		(fp_line
			(start 0.120396 0.2794)
			(end -0.12065 0.2794)
			(stroke
				(width 0.1)
				(type default)
			)
			(layer "F.Fab")
		)
		(fp_line
			(start -0.12065 0.3048)
			(end -0.67945 0.3048)
			(stroke
				(width 0.1)
				(type default)
			)
			(layer "F.Fab")
		)
		(fp_line
			(start -0.12065 0.2794)
			(end -0.12065 0.3048)
			(stroke
				(width 0.1)
				(type default)
			)
			(layer "F.Fab")
		)
		(fp_line
			(start -0.12065 -0.2794)
			(end 0.12065 -0.2794)
			(stroke
				(width 0.1)
				(type default)
			)
			(layer "F.Fab")
		)
		(fp_line
			(start -0.12065 -0.305054)
			(end -0.12065 -0.2794)
			(stroke
				(width 0.1)
				(type default)
			)
			(layer "F.Fab")
		)
		(fp_line
			(start -0.67945 0.3048)
			(end -0.67945 -0.305054)
			(stroke
				(width 0.1)
				(type default)
			)
			(layer "F.Fab")
		)
		(fp_line
			(start -0.67945 -0.305054)
			(end -0.12065 -0.305054)
			(stroke
				(width 0.1)
				(type default)
			)
			(layer "F.Fab")
		)
		(pad "1" smd circle
			(at -0.40005 0 180)
			(size 0 0)
			(layers "F.Cu" "F.Mask" "F.Paste")
			(net "M2_0_P3V3_ADC_ALERT_R")
		)
		(pad "2" smd circle
			(at 0.40005 0 180)
			(size 0 0)
			(layers "F.Cu" "F.Mask" "F.Paste")
			(net "M2_0_P3V3_ADC_ALERT")
		)
	)
	(footprint ""
		(layer "F.Cu")
		(at 69.977 -59.055 90)
		(property "Reference" "C1062"
			(at 0 0 90)
			(layer "F.SilkS")
			(hide yes)
			(effects
				(font
					(size 1.27 1.27)
				)
			)
		)
		(property "Value" ""
			(at 0 0 90)
			(layer "F.Fab")
			(effects
				(font
					(size 1.27 1.27)
				)
			)
		)
		(duplicate_pad_numbers_are_jumpers no)
		(fp_line
			(start 0.7874 -0.4064)
			(end 0.7874 0.4064)
			(stroke
				(width 0.1524)
				(type default)
			)
			(layer "F.SilkS")
		)
		(fp_line
			(start -0.7874 -0.4064)
			(end 0.7874 -0.4064)
			(stroke
				(width 0.1524)
				(type default)
			)
			(layer "F.SilkS")
		)
		(fp_line
			(start 0.7874 0.4064)
			(end -0.7874 0.4064)
			(stroke
				(width 0.1524)
				(type default)
			)
			(layer "F.SilkS")
		)
		(fp_line
			(start -0.7874 0.4064)
			(end -0.7874 -0.4064)
			(stroke
				(width 0.1524)
				(type default)
			)
			(layer "F.SilkS")
		)
		(fp_line
			(start -0.12065 -0.305054)
			(end -0.12065 -0.2794)
			(stroke
				(width 0.1)
				(type default)
			)
			(layer "F.Fab")
		)
		(fp_line
			(start -0.67945 -0.305054)
			(end -0.12065 -0.305054)
			(stroke
				(width 0.1)
				(type default)
			)
			(layer "F.Fab")
		)
		(fp_line
			(start 0.67945 -0.3048)
			(end 0.67945 0.3048)
			(stroke
				(width 0.1)
				(type default)
			)
			(layer "F.Fab")
		)
		(fp_line
			(start 0.12065 -0.3048)
			(end 0.67945 -0.3048)
			(stroke
				(width 0.1)
				(type default)
			)
			(layer "F.Fab")
		)
		(fp_line
			(start 0.12065 -0.2794)
			(end 0.12065 -0.3048)
			(stroke
				(width 0.1)
				(type default)
			)
			(layer "F.Fab")
		)
		(fp_line
			(start -0.12065 -0.2794)
			(end 0.12065 -0.2794)
			(stroke
				(width 0.1)
				(type default)
			)
			(layer "F.Fab")
		)
		(fp_line
			(start 0.120396 0.2794)
			(end -0.12065 0.2794)
			(stroke
				(width 0.1)
				(type default)
			)
			(layer "F.Fab")
		)
		(fp_line
			(start -0.12065 0.2794)
			(end -0.12065 0.3048)
			(stroke
				(width 0.1)
				(type default)
			)
			(layer "F.Fab")
		)
		(fp_line
			(start 0.67945 0.3048)
			(end 0.120396 0.3048)
			(stroke
				(width 0.1)
				(type default)
			)
			(layer "F.Fab")
		)
		(fp_line
			(start 0.120396 0.3048)
			(end 0.120396 0.2794)
			(stroke
				(width 0.1)
				(type default)
			)
			(layer "F.Fab")
		)
		(fp_line
			(start -0.12065 0.3048)
			(end -0.67945 0.3048)
			(stroke
				(width 0.1)
				(type default)
			)
			(layer "F.Fab")
		)
		(fp_line
			(start -0.67945 0.3048)
			(end -0.67945 -0.305054)
			(stroke
				(width 0.1)
				(type default)
			)
			(layer "F.Fab")
		)
		(pad "1" smd circle
			(at -0.40005 0 90)
			(size 0 0)
			(layers "F.Cu" "F.Mask" "F.Paste")
			(net "P3V3_AUX")
		)
		(pad "2" smd circle
			(at 0.40005 0 90)
			(size 0 0)
			(layers "F.Cu" "F.Mask" "F.Paste")
			(net "GND")
		)
	)
	(footprint ""
		(layer "F.Cu")
		(at 193.929 -96.103948 -90)
		(property "Reference" "R271"
			(at 0 0 270)
			(layer "F.SilkS")
			(hide yes)
			(effects
				(font
					(size 1.27 1.27)
				)
			)
		)
		(property "Value" ""
			(at 0 0 270)
			(layer "F.Fab")
			(effects
				(font
					(size 1.27 1.27)
				)
			)
		)
		(duplicate_pad_numbers_are_jumpers no)
		(fp_line
			(start -0.7874 0.4064)
			(end -0.7874 -0.4064)
			(stroke
				(width 0.1524)
				(type default)
			)
			(layer "F.SilkS")
		)
		(fp_line
			(start 0.7874 0.4064)
			(end -0.7874 0.4064)
			(stroke
				(width 0.1524)
				(type default)
			)
			(layer "F.SilkS")
		)
		(fp_line
			(start -0.7874 -0.4064)
			(end 0.7874 -0.4064)
			(stroke
				(width 0.1524)
				(type default)
			)
			(layer "F.SilkS")
		)
		(fp_line
			(start 0.7874 -0.4064)
			(end 0.7874 0.4064)
			(stroke
				(width 0.1524)
				(type default)
			)
			(layer "F.SilkS")
		)
		(fp_line
			(start -0.67945 0.3048)
			(end -0.67945 -0.305054)
			(stroke
				(width 0.1)
				(type default)
			)
			(layer "F.Fab")
		)
		(fp_line
			(start -0.12065 0.3048)
			(end -0.67945 0.3048)
			(stroke
				(width 0.1)
				(type default)
			)
			(layer "F.Fab")
		)
		(fp_line
			(start 0.120396 0.3048)
			(end 0.120396 0.2794)
			(stroke
				(width 0.1)
				(type default)
			)
			(layer "F.Fab")
		)
		(fp_line
			(start 0.67945 0.3048)
			(end 0.120396 0.3048)
			(stroke
				(width 0.1)
				(type default)
			)
			(layer "F.Fab")
		)
		(fp_line
			(start -0.12065 0.2794)
			(end -0.12065 0.3048)
			(stroke
				(width 0.1)
				(type default)
			)
			(layer "F.Fab")
		)
		(fp_line
			(start 0.120396 0.2794)
			(end -0.12065 0.2794)
			(stroke
				(width 0.1)
				(type default)
			)
			(layer "F.Fab")
		)
		(fp_line
			(start -0.12065 -0.2794)
			(end 0.12065 -0.2794)
			(stroke
				(width 0.1)
				(type default)
			)
			(layer "F.Fab")
		)
		(fp_line
			(start 0.12065 -0.2794)
			(end 0.12065 -0.3048)
			(stroke
				(width 0.1)
				(type default)
			)
			(layer "F.Fab")
		)
		(fp_line
			(start 0.12065 -0.3048)
			(end 0.67945 -0.3048)
			(stroke
				(width 0.1)
				(type default)
			)
			(layer "F.Fab")
		)
		(fp_line
			(start 0.67945 -0.3048)
			(end 0.67945 0.3048)
			(stroke
				(width 0.1)
				(type default)
			)
			(layer "F.Fab")
		)
		(fp_line
			(start -0.67945 -0.305054)
			(end -0.12065 -0.305054)
			(stroke
				(width 0.1)
				(type default)
			)
			(layer "F.Fab")
		)
		(fp_line
			(start -0.12065 -0.305054)
			(end -0.12065 -0.2794)
			(stroke
				(width 0.1)
				(type default)
			)
			(layer "F.Fab")
		)
		(pad "1" smd circle
			(at -0.40005 0 270)
			(size 0 0)
			(layers "F.Cu" "F.Mask" "F.Paste")
			(net "FM_PRSNT_CPU1_R_N")
		)
		(pad "2" smd circle
			(at 0.40005 0 270)
			(size 0 0)
			(layers "F.Cu" "F.Mask" "F.Paste")
			(net "FM_PRSNT_CPU1_N")
		)
	)
	(footprint ""
		(layer "F.Cu")
		(at 45.25391 -337.403948)
		(property "Reference" "PL48"
			(at -3.115056 -15.887446 0)
			(unlocked yes)
			(layer "F.SilkS")
			(effects
				(font
					(size 0.7874 0.5842)
					(thickness 0.1524)
				)
				(justify left)
			)
		)
		(property "Value" ""
			(at 0 0 0)
			(layer "F.Fab")
			(effects
				(font
					(size 1.27 1.27)
				)
			)
		)
		(duplicate_pad_numbers_are_jumpers no)
		(fp_line
			(start -3.750056 -5.500116)
			(end -2.393442 -5.500116)
			(stroke
				(width 0.1524)
				(type default)
			)
			(layer "F.SilkS")
		)
		(fp_line
			(start -3.750056 5.500116)
			(end -3.750056 -5.500116)
			(stroke
				(width 0.1524)
				(type default)
			)
			(layer "F.SilkS")
		)
		(fp_line
			(start -2.393442 5.500116)
			(end -3.750056 5.500116)
			(stroke
				(width 0.1524)
				(type default)
			)
			(layer "F.SilkS")
		)
		(fp_line
			(start 2.393442 5.500116)
			(end 3.750056 5.500116)
			(stroke
				(width 0.1524)
				(type default)
			)
			(layer "F.SilkS")
		)
		(fp_line
			(start 3.750056 -5.500116)
			(end 2.393442 -5.500116)
			(stroke
				(width 0.1524)
				(type default)
			)
			(layer "F.SilkS")
		)
		(fp_line
			(start 3.750056 5.500116)
			(end 3.750056 -5.500116)
			(stroke
				(width 0.1524)
				(type default)
			)
			(layer "F.SilkS")
		)
		(fp_poly
			(pts
				(xy -3.9116 -4.249928) (xy -4.35991 -4.0259) (xy -4.35991 -4.473956)
			)
			(stroke
				(width 0)
				(type default)
			)
			(fill yes)
			(layer "F.SilkS")
		)
		(fp_line
			(start -3.750056 -5.500116)
			(end -3.750056 5.500116)
			(stroke
				(width 0.1)
				(type default)
			)
			(layer "F.Fab")
		)
		(fp_line
			(start -3.750056 5.500116)
			(end 3.750056 5.500116)
			(stroke
				(width 0.1)
				(type default)
			)
			(layer "F.Fab")
		)
		(fp_line
			(start 3.750056 -5.500116)
			(end -3.750056 -5.500116)
			(stroke
				(width 0.1)
				(type default)
			)
			(layer "F.Fab")
		)
		(fp_line
			(start 3.750056 5.500116)
			(end 3.750056 -5.500116)
			(stroke
				(width 0.1)
				(type default)
			)
			(layer "F.Fab")
		)
		(fp_poly
			(pts
				(xy -4.9276 -4.757928) (xy -4.9276 -3.741928) (xy -3.9116 -4.249928)
			)
			(stroke
				(width 0)
				(type default)
			)
			(fill yes)
			(layer "F.Fab")
		)
		(pad "1" smd rect
			(at 0 -4.249928 270)
			(size 2.413 4.5212)
			(layers "F.Cu" "F.Mask" "F.Paste")
			(net "SW_PVDDIO_P1_SW2")
		)
		(pad "2" smd rect
			(at 0 -1.175004 270)
			(size 1.3716 4.5212)
			(layers "F.Cu" "F.Mask" "F.Paste")
			(net "IND_PVDDIO_P1_CPL3")
		)
		(pad "3" smd rect
			(at 0 1.175004 270)
			(size 1.3716 4.5212)
			(layers "F.Cu" "F.Mask" "F.Paste")
			(net "IND_PVDDIO_P1_CPL2")
		)
		(pad "4" smd rect
			(at 0 4.249928 270)
			(size 2.413 4.5212)
			(layers "F.Cu" "F.Mask" "F.Paste")
			(net "PVDDIO_P1")
		)
	)
)
